FILE_TYPE = CONNECTIVITY;
{Allegro Design Entry HDL 17.2-2016 S066 (3851973) 4/6/2020}
"PAGE_NUMBER" = 2;
0"NC";
END.
